(kicad_pcb
	(version 20241229)
	(generator "pcbnew")
	(generator_version "9.0")
	(general
		(thickness 1.6642)
		(legacy_teardrops no)
	)
	(paper "A3")
	(title_block
		(title "PolarFire SoM")
		(date "2025-07-22")
		(rev "1.1.4")
		(company "Antmicro Ltd")
		(comment 1 "www.antmicro.com")
		(comment 9 "footprints 187-190 of 470")
	)
	(layers
		(0 "F.Cu" mixed)
		(4 "In1.Cu" power)
		(6 "In2.Cu" signal)
		(8 "In3.Cu" power)
		(10 "In4.Cu" signal)
		(12 "In5.Cu" power)
		(14 "In6.Cu" power)
		(16 "In7.Cu" signal)
		(18 "In8.Cu" power)
		(20 "In9.Cu" signal)
		(22 "In10.Cu" power)
		(24 "In11.Cu" signal)
		(26 "In12.Cu" signal)
		(2 "B.Cu" mixed)
		(9 "F.Adhes" user "F.Adhesive")
		(11 "B.Adhes" user "B.Adhesive")
		(13 "F.Paste" user)
		(15 "B.Paste" user)
		(5 "F.SilkS" user "F.Silkscreen")
		(7 "B.SilkS" user "B.Silkscreen")
		(1 "F.Mask" user)
		(3 "B.Mask" user)
		(17 "Dwgs.User" user "User.Drawings")
		(19 "Cmts.User" user "User.Comments")
		(21 "Eco1.User" user "User.Eco1")
		(23 "Eco2.User" user "User.Eco2")
		(25 "Edge.Cuts" user)
		(27 "Margin" user)
		(31 "F.CrtYd" user "F.Courtyard")
		(29 "B.CrtYd" user "B.Courtyard")
		(35 "F.Fab" user)
		(33 "B.Fab" user)
	)
	(footprint "antmicro-footprints:C_0402_1005Metric"
		(layer "B.Cu")
		(at 193.45 146.75 90)
		(descr "Capacitor SMD 0402")
		(tags "capacitor SMD 0402")
		(property "Reference" "C187"
			(at -3.65 0.6 90)
			(layer "B.SilkS")
			(effects
				(font
					(size 0.7 0.7)
					(thickness 0.15)
				)
				(justify right bottom mirror)
			)
		)
		(property "Value" "C_100n_0402"
			(at -1.022927 -2.155213 90)
			(layer "B.Fab")
			(hide yes)
			(effects
				(font
					(size 0.7 0.7)
					(thickness 0.15)
				)
				(justify right bottom mirror)
			)
		)
		(property "Datasheet" "https://www.murata.com/products/productdetail?partno=GRM155R61H104KE14%23"
			(at 0 0 90)
			(layer "F.Fab")
			(hide yes)
			(effects
				(font
					(size 1.27 1.27)
					(thickness 0.15)
				)
			)
		)
		(property "Description" "SMD Multilayer Ceramic Capacitor, 0.1 µF, 50 V, 0402 [1005 Metric], ± 10%, X5R, GRM Series"
			(at 0 0 90)
			(layer "F.Fab")
			(hide yes)
			(effects
				(font
					(size 1.27 1.27)
					(thickness 0.15)
				)
			)
		)
		(property "Author" "Antmicro"
			(at 340.2 -46.7 0)
			(layer "B.Fab")
			(hide yes)
			(effects
				(font
					(size 1 1)
					(thickness 0.15)
				)
				(justify mirror)
			)
		)
		(property "Dielectric" "X5R"
			(at 340.2 -46.7 0)
			(layer "B.Fab")
			(hide yes)
			(effects
				(font
					(size 1 1)
					(thickness 0.15)
				)
				(justify mirror)
			)
		)
		(property "License" "Apache-2.0"
			(at 340.2 -46.7 0)
			(layer "B.Fab")
			(hide yes)
			(effects
				(font
					(size 1 1)
					(thickness 0.15)
				)
				(justify mirror)
			)
		)
		(property "MPN" "GRM155R61H104KE14D"
			(at 340.2 -46.7 0)
			(layer "B.Fab")
			(hide yes)
			(effects
				(font
					(size 1 1)
					(thickness 0.15)
				)
				(justify mirror)
			)
		)
		(property "Manufacturer" "Murata"
			(at 340.2 -46.7 0)
			(layer "B.Fab")
			(hide yes)
			(effects
				(font
					(size 1 1)
					(thickness 0.15)
				)
				(justify mirror)
			)
		)
		(property "Public" ""
			(at 340.2 -46.7 0)
			(layer "B.Fab")
			(hide yes)
			(effects
				(font
					(size 1 1)
					(thickness 0.15)
				)
				(justify mirror)
			)
		)
		(property "Val" "100n"
			(at 340.2 -46.7 0)
			(layer "B.Fab")
			(hide yes)
			(effects
				(font
					(size 1 1)
					(thickness 0.15)
				)
				(justify mirror)
			)
		)
		(property "Voltage" "50V"
			(at 340.2 -46.7 0)
			(layer "B.Fab")
			(hide yes)
			(effects
				(font
					(size 1 1)
					(thickness 0.15)
				)
				(justify mirror)
			)
		)
		(sheetname "/HDMI/")
		(sheetfile "hdmi.kicad_sch")
		(attr smd)
		(fp_rect
			(start -0.925 0.47)
			(end 0.925 -0.47)
			(stroke
				(width 0.05)
				(type default)
			)
			(fill no)
			(layer "B.CrtYd")
		)
		(fp_line
			(start 0.504 -0.248)
			(end -0.494 -0.248)
			(stroke
				(width 0.15)
				(type solid)
			)
			(layer "B.Fab")
		)
		(fp_line
			(start -0.494 -0.248)
			(end -0.494 0.25)
			(stroke
				(width 0.15)
				(type solid)
			)
			(layer "B.Fab")
		)
		(fp_line
			(start 0.504 0.25)
			(end 0.504 -0.248)
			(stroke
				(width 0.15)
				(type solid)
			)
			(layer "B.Fab")
		)
		(fp_line
			(start -0.494 0.25)
			(end 0.504 0.25)
			(stroke
				(width 0.15)
				(type solid)
			)
			(layer "B.Fab")
		)
		(fp_text user "${REFERENCE}"
			(at -0.939 -4.599 270)
			(layer "B.Fab")
			(effects
				(font
					(size 0.7 0.7)
					(thickness 0.15)
				)
				(justify left bottom mirror)
			)
		)
		(fp_text user "Author: Antmicro"
			(at -0.939 -3.399 270)
			(layer "B.Fab")
			(effects
				(font
					(size 0.7 0.7)
					(thickness 0.15)
				)
				(justify left bottom mirror)
			)
		)
		(fp_text user "License: Apache-2.0"
			(at -0.939 -5.799 270)
			(layer "B.Fab")
			(effects
				(font
					(size 0.7 0.7)
					(thickness 0.15)
				)
				(justify left bottom mirror)
			)
		)
		(pad "1" smd roundrect
			(at -0.48 0 90)
			(size 0.59 0.64)
			(layers "B.Cu" "B.Mask" "B.Paste")
			(roundrect_rratio 0.25)
			(net 553 "/HDMI/HDMI_3V3")
			(pintype "passive")
		)
		(pad "2" smd roundrect
			(at 0.48 0 90)
			(size 0.59 0.64)
			(layers "B.Cu" "B.Mask" "B.Paste")
			(roundrect_rratio 0.25)
			(net 417 "GND")
			(pintype "passive")
		)
	)
	(footprint "antmicro-footprints:C_0402_1005Metric"
		(layer "B.Cu")
		(at 197.99 136.664 90)
		(descr "Capacitor SMD 0402")
		(tags "capacitor SMD 0402")
		(property "Reference" "C37"
			(at 4.564 -9.615 90)
			(layer "B.SilkS")
			(effects
				(font
					(size 0.7 0.7)
					(thickness 0.15)
				)
				(justify right bottom mirror)
			)
		)
		(property "Value" "C_100n_0402"
			(at -1.022927 -2.155213 90)
			(layer "B.Fab")
			(hide yes)
			(effects
				(font
					(size 0.7 0.7)
					(thickness 0.15)
				)
				(justify right bottom mirror)
			)
		)
		(property "Datasheet" "https://www.murata.com/products/productdetail?partno=GRM155R61H104KE14%23"
			(at 0 0 90)
			(layer "F.Fab")
			(hide yes)
			(effects
				(font
					(size 1.27 1.27)
					(thickness 0.15)
				)
			)
		)
		(property "Description" "SMD Multilayer Ceramic Capacitor, 0.1 µF, 50 V, 0402 [1005 Metric], ± 10%, X5R, GRM Series"
			(at 0 0 90)
			(layer "F.Fab")
			(hide yes)
			(effects
				(font
					(size 1.27 1.27)
					(thickness 0.15)
				)
			)
		)
		(property "Author" "Antmicro"
			(at 334.654 -61.326 0)
			(layer "B.Fab")
			(hide yes)
			(effects
				(font
					(size 1 1)
					(thickness 0.15)
				)
				(justify mirror)
			)
		)
		(property "Dielectric" "X5R"
			(at 334.654 -61.326 0)
			(layer "B.Fab")
			(hide yes)
			(effects
				(font
					(size 1 1)
					(thickness 0.15)
				)
				(justify mirror)
			)
		)
		(property "License" "Apache-2.0"
			(at 334.654 -61.326 0)
			(layer "B.Fab")
			(hide yes)
			(effects
				(font
					(size 1 1)
					(thickness 0.15)
				)
				(justify mirror)
			)
		)
		(property "MPN" "GRM155R61H104KE14D"
			(at 334.654 -61.326 0)
			(layer "B.Fab")
			(hide yes)
			(effects
				(font
					(size 1 1)
					(thickness 0.15)
				)
				(justify mirror)
			)
		)
		(property "Manufacturer" "Murata"
			(at 334.654 -61.326 0)
			(layer "B.Fab")
			(hide yes)
			(effects
				(font
					(size 1 1)
					(thickness 0.15)
				)
				(justify mirror)
			)
		)
		(property "Public" ""
			(at 334.654 -61.326 0)
			(layer "B.Fab")
			(hide yes)
			(effects
				(font
					(size 1 1)
					(thickness 0.15)
				)
				(justify mirror)
			)
		)
		(property "Val" "100n"
			(at 334.654 -61.326 0)
			(layer "B.Fab")
			(hide yes)
			(effects
				(font
					(size 1 1)
					(thickness 0.15)
				)
				(justify mirror)
			)
		)
		(property "Voltage" "50V"
			(at 334.654 -61.326 0)
			(layer "B.Fab")
			(hide yes)
			(effects
				(font
					(size 1 1)
					(thickness 0.15)
				)
				(justify mirror)
			)
		)
		(sheetname "/FPGA Supply/")
		(sheetfile "fpga-supply.kicad_sch")
		(attr smd)
		(fp_rect
			(start -0.925 0.47)
			(end 0.925 -0.47)
			(stroke
				(width 0.05)
				(type default)
			)
			(fill no)
			(layer "B.CrtYd")
		)
		(fp_line
			(start 0.504 -0.248)
			(end -0.494 -0.248)
			(stroke
				(width 0.15)
				(type solid)
			)
			(layer "B.Fab")
		)
		(fp_line
			(start -0.494 -0.248)
			(end -0.494 0.25)
			(stroke
				(width 0.15)
				(type solid)
			)
			(layer "B.Fab")
		)
		(fp_line
			(start 0.504 0.25)
			(end 0.504 -0.248)
			(stroke
				(width 0.15)
				(type solid)
			)
			(layer "B.Fab")
		)
		(fp_line
			(start -0.494 0.25)
			(end 0.504 0.25)
			(stroke
				(width 0.15)
				(type solid)
			)
			(layer "B.Fab")
		)
		(fp_text user "Author: Antmicro"
			(at -0.939 -3.399 270)
			(layer "B.Fab")
			(effects
				(font
					(size 0.7 0.7)
					(thickness 0.15)
				)
				(justify left bottom mirror)
			)
		)
		(fp_text user "${REFERENCE}"
			(at -0.939 -4.599 270)
			(layer "B.Fab")
			(effects
				(font
					(size 0.7 0.7)
					(thickness 0.15)
				)
				(justify left bottom mirror)
			)
		)
		(fp_text user "License: Apache-2.0"
			(at -0.939 -5.799 270)
			(layer "B.Fab")
			(effects
				(font
					(size 0.7 0.7)
					(thickness 0.15)
				)
				(justify left bottom mirror)
			)
		)
		(pad "1" smd roundrect
			(at -0.48 0 90)
			(size 0.59 0.64)
			(layers "B.Cu" "B.Mask" "B.Paste")
			(roundrect_rratio 0.25)
			(net 417 "GND")
			(pintype "passive")
		)
		(pad "2" smd roundrect
			(at 0.48 0 90)
			(size 0.59 0.64)
			(layers "B.Cu" "B.Mask" "B.Paste")
			(roundrect_rratio 0.25)
			(net 418 "+2V5")
			(pintype "passive")
		)
	)
	(footprint "antmicro-footprints:C_0402_1005Metric"
		(layer "B.Cu")
		(at 179.934359 147.659391 180)
		(descr "Capacitor SMD 0402")
		(tags "capacitor SMD 0402")
		(property "Reference" "C91"
			(at -1.805641 -1.450609 0)
			(layer "B.SilkS")
			(effects
				(font
					(size 0.7 0.7)
					(thickness 0.15)
				)
				(justify left bottom mirror)
			)
		)
		(property "Value" "C_22u_0402"
			(at -1.022927 -2.155213 0)
			(layer "B.Fab")
			(hide yes)
			(effects
				(font
					(size 0.7 0.7)
					(thickness 0.15)
				)
				(justify left bottom mirror)
			)
		)
		(property "Datasheet" "https://www.murata.com/products/productdetail?partno=GRM158R60J226ME01%23"
			(at 0 0 180)
			(layer "F.Fab")
			(hide yes)
			(effects
				(font
					(size 1.27 1.27)
					(thickness 0.15)
				)
			)
		)
		(property "Description" "SMD Multilayer Ceramic Capacitor, 22 uF, 4 V, 0402 [1005 Metric], X6S"
			(at 0 0 180)
			(layer "F.Fab")
			(hide yes)
			(effects
				(font
					(size 1.27 1.27)
					(thickness 0.15)
				)
			)
		)
		(property "Author" "Antmicro"
			(at 359.868718 295.318782 0)
			(layer "B.Fab")
			(hide yes)
			(effects
				(font
					(size 1 1)
					(thickness 0.15)
				)
				(justify mirror)
			)
		)
		(property "Dielectric" ""
			(at 359.868718 295.318782 0)
			(layer "B.Fab")
			(hide yes)
			(effects
				(font
					(size 1 1)
					(thickness 0.15)
				)
				(justify mirror)
			)
		)
		(property "License" "Apache-2.0"
			(at 359.868718 295.318782 0)
			(layer "B.Fab")
			(hide yes)
			(effects
				(font
					(size 1 1)
					(thickness 0.15)
				)
				(justify mirror)
			)
		)
		(property "MPN" "GRM158R60J226ME01D"
			(at 359.868718 295.318782 0)
			(layer "B.Fab")
			(hide yes)
			(effects
				(font
					(size 1 1)
					(thickness 0.15)
				)
				(justify mirror)
			)
		)
		(property "Manufacturer" "Murata"
			(at 359.868718 295.318782 0)
			(layer "B.Fab")
			(hide yes)
			(effects
				(font
					(size 1 1)
					(thickness 0.15)
				)
				(justify mirror)
			)
		)
		(property "Public" ""
			(at 359.868718 295.318782 0)
			(layer "B.Fab")
			(hide yes)
			(effects
				(font
					(size 1 1)
					(thickness 0.15)
				)
				(justify mirror)
			)
		)
		(property "Val" "22u"
			(at 359.868718 295.318782 0)
			(layer "B.Fab")
			(hide yes)
			(effects
				(font
					(size 1 1)
					(thickness 0.15)
				)
				(justify mirror)
			)
		)
		(property "Voltage" ""
			(at 359.868718 295.318782 0)
			(layer "B.Fab")
			(hide yes)
			(effects
				(font
					(size 1 1)
					(thickness 0.15)
				)
				(justify mirror)
			)
		)
		(sheetname "/Supply/")
		(sheetfile "supply.kicad_sch")
		(attr smd)
		(fp_rect
			(start -0.925 0.47)
			(end 0.925 -0.47)
			(stroke
				(width 0.05)
				(type default)
			)
			(fill no)
			(layer "B.CrtYd")
		)
		(fp_line
			(start 0.504 0.25)
			(end 0.504 -0.248)
			(stroke
				(width 0.15)
				(type solid)
			)
			(layer "B.Fab")
		)
		(fp_line
			(start 0.504 -0.248)
			(end -0.494 -0.248)
			(stroke
				(width 0.15)
				(type solid)
			)
			(layer "B.Fab")
		)
		(fp_line
			(start -0.494 0.25)
			(end 0.504 0.25)
			(stroke
				(width 0.15)
				(type solid)
			)
			(layer "B.Fab")
		)
		(fp_line
			(start -0.494 -0.248)
			(end -0.494 0.25)
			(stroke
				(width 0.15)
				(type solid)
			)
			(layer "B.Fab")
		)
		(fp_text user "${REFERENCE}"
			(at -0.939 -4.599 0)
			(layer "B.Fab")
			(effects
				(font
					(size 0.7 0.7)
					(thickness 0.15)
				)
				(justify left bottom mirror)
			)
		)
		(fp_text user "License: Apache-2.0"
			(at -0.939 -5.799 0)
			(layer "B.Fab")
			(effects
				(font
					(size 0.7 0.7)
					(thickness 0.15)
				)
				(justify left bottom mirror)
			)
		)
		(fp_text user "Author: Antmicro"
			(at -0.939 -3.399 0)
			(layer "B.Fab")
			(effects
				(font
					(size 0.7 0.7)
					(thickness 0.15)
				)
				(justify left bottom mirror)
			)
		)
		(pad "1" smd roundrect
			(at -0.48 0 180)
			(size 0.59 0.64)
			(layers "B.Cu" "B.Mask" "B.Paste")
			(roundrect_rratio 0.25)
			(net 417 "GND")
			(pintype "passive")
		)
		(pad "2" smd roundrect
			(at 0.48 0 180)
			(size 0.59 0.64)
			(layers "B.Cu" "B.Mask" "B.Paste")
			(roundrect_rratio 0.25)
			(net 90 "+5V")
			(pintype "passive")
		)
	)
	(footprint "antmicro-footprints:R_0402_1005Metric"
		(layer "B.Cu")
		(at 212.6425 126.812 -90)
		(descr "Resistor SMD 0402")
		(tags "resistor SMD 0402")
		(property "Reference" "R35"
			(at 0.688 -0.3825 90)
			(layer "B.SilkS")
			(effects
				(font
					(size 0.7 0.7)
					(thickness 0.15)
				)
				(justify left bottom mirror)
			)
		)
		(property "Value" "R_49k9_0402"
			(at -1.011843 -1.772047 90)
			(layer "B.Fab")
			(hide yes)
			(effects
				(font
					(size 0.7 0.7)
					(thickness 0.15)
				)
				(justify left bottom mirror)
			)
		)
		(property "Datasheet" "https://www.bourns.com/docs/product-datasheets/cr.pdf"
			(at 0 0 270)
			(layer "F.Fab")
			(hide yes)
			(effects
				(font
					(size 1.27 1.27)
					(thickness 0.15)
				)
			)
		)
		(property "Description" "SMD Chip Resistor, 49.9 kohm, ± 1%, 63 mW, 0402 [1005 Metric], Thick Film, General Purpose"
			(at 0 0 270)
			(layer "F.Fab")
			(hide yes)
			(effects
				(font
					(size 1.27 1.27)
					(thickness 0.15)
				)
			)
		)
		(property "Author" "Antmicro"
			(at 85.8305 339.4545 0)
			(layer "B.Fab")
			(hide yes)
			(effects
				(font
					(size 1 1)
					(thickness 0.15)
				)
				(justify mirror)
			)
		)
		(property "License" "Apache-2.0"
			(at 85.8305 339.4545 0)
			(layer "B.Fab")
			(hide yes)
			(effects
				(font
					(size 1 1)
					(thickness 0.15)
				)
				(justify mirror)
			)
		)
		(property "MPN" "CR0402-FX-4992GLF"
			(at 85.8305 339.4545 0)
			(layer "B.Fab")
			(hide yes)
			(effects
				(font
					(size 1 1)
					(thickness 0.15)
				)
				(justify mirror)
			)
		)
		(property "Manufacturer" "Bourns"
			(at 85.8305 339.4545 0)
			(layer "B.Fab")
			(hide yes)
			(effects
				(font
					(size 1 1)
					(thickness 0.15)
				)
				(justify mirror)
			)
		)
		(property "Public" ""
			(at 85.8305 339.4545 0)
			(layer "B.Fab")
			(hide yes)
			(effects
				(font
					(size 1 1)
					(thickness 0.15)
				)
				(justify mirror)
			)
		)
		(property "Tolerance" "1%"
			(at 85.8305 339.4545 0)
			(layer "B.Fab")
			(hide yes)
			(effects
				(font
					(size 1 1)
					(thickness 0.15)
				)
				(justify mirror)
			)
		)
		(property "Val" "49k9"
			(at 85.8305 339.4545 0)
			(layer "B.Fab")
			(hide yes)
			(effects
				(font
					(size 1 1)
					(thickness 0.15)
				)
				(justify mirror)
			)
		)
		(sheetname "/Memory/")
		(sheetfile "memory.kicad_sch")
		(attr smd)
		(fp_rect
			(start -0.925 0.47)
			(end 0.925 -0.47)
			(stroke
				(width 0.05)
				(type default)
			)
			(fill no)
			(layer "B.CrtYd")
		)
		(fp_rect
			(start -0.5 0.25)
			(end 0.5 -0.25)
			(stroke
				(width 0.15)
				(type solid)
			)
			(fill no)
			(layer "B.Fab")
		)
		(fp_text user "Author: Antmicro"
			(at -0.95 -4.169 90)
			(layer "B.Fab")
			(effects
				(font
					(size 0.7 0.7)
					(thickness 0.15)
				)
				(justify left bottom mirror)
			)
		)
		(fp_text user "License: Apache-2.0"
			(at -0.95 -5.169 90)
			(layer "B.Fab")
			(effects
				(font
					(size 0.7 0.7)
					(thickness 0.15)
				)
				(justify left bottom mirror)
			)
		)
		(fp_text user "${REFERENCE}"
			(at -0.95 -3.168 90)
			(layer "B.Fab")
			(effects
				(font
					(size 0.7 0.7)
					(thickness 0.15)
				)
				(justify left bottom mirror)
			)
		)
		(pad "1" smd roundrect
			(at -0.48 0 270)
			(size 0.59 0.64)
			(layers "B.Cu" "B.Mask" "B.Paste")
			(roundrect_rratio 0.25)
			(net 207 "/FPGA MSSIO/EMMC.DAT3")
			(pintype "passive")
		)
		(pad "2" smd roundrect
			(at 0.48 0 270)
			(size 0.59 0.64)
			(layers "B.Cu" "B.Mask" "B.Paste")
			(roundrect_rratio 0.25)
			(net 137 "SD_VDD")
			(pintype "passive")
		)
	)
)
